(kicad_pcb
	(version 20241229)
	(generator "pcbnew")
	(generator_version "9.0")
	(general
		(thickness 1.6)
		(legacy_teardrops no)
	)
	(paper "A4")
	(title_block
		(title "OCuLink to PCIe adapter")
		(date "2025-06-18")
		(rev "1.0.0")
		(company "Antmicro Ltd")
		(comment 1 "www.antmicro.com")
		(comment 9 "footprints 68-72 of 159")
	)
	(layers
		(0 "F.Cu" signal)
		(4 "In1.Cu" signal)
		(6 "In2.Cu" signal)
		(2 "B.Cu" signal)
		(9 "F.Adhes" user "F.Adhesive")
		(11 "B.Adhes" user "B.Adhesive")
		(13 "F.Paste" user)
		(15 "B.Paste" user)
		(5 "F.SilkS" user "F.Silkscreen")
		(7 "B.SilkS" user "B.Silkscreen")
		(1 "F.Mask" user)
		(3 "B.Mask" user)
		(17 "Dwgs.User" user "User.Drawings")
		(19 "Cmts.User" user "User.Comments")
		(21 "Eco1.User" user "User.Eco1")
		(23 "Eco2.User" user "User.Eco2")
		(25 "Edge.Cuts" user)
		(27 "Margin" user)
		(31 "F.CrtYd" user "F.Courtyard")
		(29 "B.CrtYd" user "B.Courtyard")
		(35 "F.Fab" user)
		(33 "B.Fab" user)
	)
	(footprint "antmicro-footprints:R_0603_1608Metric"
		(layer "F.Cu")
		(at 132.4 100.8)
		(descr "Resistor SMD 0603")
		(tags "resistor SMD 0603")
		(property "Reference" "R26"
			(at -3.6 0.4 180)
			(layer "F.SilkS")
			(effects
				(font
					(size 0.7 0.7)
					(thickness 0.15)
				)
				(justify left bottom)
			)
		)
		(property "Value" "R_0R_22.4A_0603"
			(at 0 1.6 0)
			(layer "F.Fab")
			(effects
				(font
					(size 0.7 0.7)
					(thickness 0.15)
				)
				(justify left bottom)
			)
		)
		(property "Datasheet" "https://fscdn.rohm.com/en/products/databook/datasheet/passive/resistor/chip_resistor/pmr-jpw-e.pdf"
			(at 0 0 0)
			(layer "F.Fab")
			(hide yes)
			(effects
				(font
					(size 1.27 1.27)
					(thickness 0.15)
				)
			)
		)
		(property "Description" "SMD Chip Resistor"
			(at 0 0 0)
			(layer "F.Fab")
			(hide yes)
			(effects
				(font
					(size 1.27 1.27)
					(thickness 0.15)
				)
			)
		)
		(property "MPN" "PMR03EZPJ000"
			(at 0 0 0)
			(unlocked yes)
			(layer "F.Fab")
			(hide yes)
			(effects
				(font
					(size 1 1)
					(thickness 0.15)
				)
			)
		)
		(property "Manufacturer" "ROHM Semiconductor"
			(at 0 0 0)
			(unlocked yes)
			(layer "F.Fab")
			(hide yes)
			(effects
				(font
					(size 1 1)
					(thickness 0.15)
				)
			)
		)
		(property "Val" "0R"
			(at 0 0 0)
			(unlocked yes)
			(layer "F.Fab")
			(hide yes)
			(effects
				(font
					(size 1 1)
					(thickness 0.15)
				)
			)
		)
		(property "Max. Curr." "22.4A"
			(at 0 0 0)
			(unlocked yes)
			(layer "F.Fab")
			(hide yes)
			(effects
				(font
					(size 1 1)
					(thickness 0.15)
				)
			)
		)
		(property "Author" "Antmicro"
			(at 0 0 0)
			(unlocked yes)
			(layer "F.Fab")
			(hide yes)
			(effects
				(font
					(size 1 1)
					(thickness 0.15)
				)
			)
		)
		(property "License" "Apache-2.0"
			(at 0 0 0)
			(unlocked yes)
			(layer "F.Fab")
			(hide yes)
			(effects
				(font
					(size 1 1)
					(thickness 0.15)
				)
			)
		)
		(property "Tolerance" "template_tolerance"
			(at 0 0 0)
			(unlocked yes)
			(layer "F.Fab")
			(hide yes)
			(effects
				(font
					(size 1 1)
					(thickness 0.15)
				)
			)
		)
		(sheetname "/USB-PD/")
		(sheetfile "usb-pd.kicad_sch")
		(attr smd exclude_from_bom)
		(fp_line
			(start -0.15 -0.4)
			(end 0.15 -0.4)
			(stroke
				(width 0.15)
				(type solid)
			)
			(layer "F.SilkS")
		)
		(fp_line
			(start -0.15 0.4)
			(end 0.15 0.4)
			(stroke
				(width 0.15)
				(type solid)
			)
			(layer "F.SilkS")
		)
		(fp_rect
			(start -1.25 -0.65)
			(end 1.25 0.65)
			(stroke
				(width 0.05)
				(type solid)
			)
			(fill no)
			(layer "F.CrtYd")
		)
		(fp_rect
			(start -0.8 -0.4)
			(end 0.8 0.4)
			(stroke
				(width 0.15)
				(type solid)
			)
			(fill no)
			(layer "F.Fab")
		)
		(fp_text user "${REFERENCE}"
			(at -1.25 3.898 0)
			(layer "F.Fab")
			(effects
				(font
					(size 0.7 0.7)
					(thickness 0.15)
				)
				(justify left bottom)
			)
		)
		(fp_text user "License: Apache-2.0"
			(at -1.25 5.9 0)
			(layer "F.Fab")
			(effects
				(font
					(size 0.7 0.7)
					(thickness 0.15)
				)
				(justify left bottom)
			)
		)
		(fp_text user "Author: Antmicro"
			(at -1.25 4.9 0)
			(layer "F.Fab")
			(effects
				(font
					(size 0.7 0.7)
					(thickness 0.15)
				)
				(justify left bottom)
			)
		)
		(pad "1" smd roundrect
			(at -0.7 0)
			(size 0.8 1)
			(layers "F.Cu" "F.Mask" "F.Paste")
			(roundrect_rratio 0.2)
			(net 119 "/Power/VCC_PD")
			(pintype "passive")
		)
		(pad "2" smd roundrect
			(at 0.7 0)
			(size 0.8 1)
			(layers "F.Cu" "F.Mask" "F.Paste")
			(roundrect_rratio 0.2)
			(net 187 "/USB-PD/12V_CONV")
			(pintype "passive")
		)
	)
	(footprint "antmicro-footprints:C_0402_1005Metric"
		(layer "F.Cu")
		(at 148.152 96)
		(descr "Capacitor SMD 0402")
		(tags "capacitor SMD 0402")
		(property "Reference" "C31"
			(at 1.248 0.4 180)
			(layer "F.SilkS")
			(effects
				(font
					(size 0.7 0.7)
					(thickness 0.15)
				)
				(justify left bottom)
			)
		)
		(property "Value" "C_100n_0402"
			(at -1.022927 2.155213 0)
			(layer "F.Fab")
			(effects
				(font
					(size 0.7 0.7)
					(thickness 0.15)
				)
				(justify left bottom)
			)
		)
		(property "Datasheet" "https://www.murata.com/products/productdetail?partno=GRM155R61H104KE14%23"
			(at 0 0 0)
			(layer "F.Fab")
			(hide yes)
			(effects
				(font
					(size 1.27 1.27)
					(thickness 0.15)
				)
			)
		)
		(property "Description" "SMD Multilayer Ceramic Capacitor, 0.1 µF, 50 V, 0402 [1005 Metric], ± 10%, X5R, GRM Series"
			(at 0 0 0)
			(layer "F.Fab")
			(hide yes)
			(effects
				(font
					(size 1.27 1.27)
					(thickness 0.15)
				)
			)
		)
		(property "MPN" "GRM155R61H104KE14D"
			(at 0 0 0)
			(unlocked yes)
			(layer "F.Fab")
			(hide yes)
			(effects
				(font
					(size 1 1)
					(thickness 0.15)
				)
			)
		)
		(property "Val" "100n"
			(at 0 0 0)
			(unlocked yes)
			(layer "F.Fab")
			(hide yes)
			(effects
				(font
					(size 1 1)
					(thickness 0.15)
				)
			)
		)
		(property "Voltage" "50V"
			(at 0 0 0)
			(unlocked yes)
			(layer "F.Fab")
			(hide yes)
			(effects
				(font
					(size 1 1)
					(thickness 0.15)
				)
			)
		)
		(property "Dielectric" "X5R"
			(at 0 0 0)
			(unlocked yes)
			(layer "F.Fab")
			(hide yes)
			(effects
				(font
					(size 1 1)
					(thickness 0.15)
				)
			)
		)
		(property "Manufacturer" "Murata"
			(at 0 0 0)
			(unlocked yes)
			(layer "F.Fab")
			(hide yes)
			(effects
				(font
					(size 1 1)
					(thickness 0.15)
				)
			)
		)
		(property "License" "Apache-2.0"
			(at 0 0 0)
			(unlocked yes)
			(layer "F.Fab")
			(hide yes)
			(effects
				(font
					(size 1 1)
					(thickness 0.15)
				)
			)
		)
		(property "Author" "Antmicro"
			(at 0 0 0)
			(unlocked yes)
			(layer "F.Fab")
			(hide yes)
			(effects
				(font
					(size 1 1)
					(thickness 0.15)
				)
			)
		)
		(sheetname "/USB-PD/")
		(sheetfile "usb-pd.kicad_sch")
		(attr smd)
		(fp_rect
			(start -0.925 -0.47)
			(end 0.925 0.47)
			(stroke
				(width 0.05)
				(type default)
			)
			(fill no)
			(layer "F.CrtYd")
		)
		(fp_line
			(start -0.494 -0.25)
			(end 0.504 -0.25)
			(stroke
				(width 0.15)
				(type solid)
			)
			(layer "F.Fab")
		)
		(fp_line
			(start -0.494 0.248)
			(end -0.494 -0.25)
			(stroke
				(width 0.15)
				(type solid)
			)
			(layer "F.Fab")
		)
		(fp_line
			(start 0.504 -0.25)
			(end 0.504 0.248)
			(stroke
				(width 0.15)
				(type solid)
			)
			(layer "F.Fab")
		)
		(fp_line
			(start 0.504 0.248)
			(end -0.494 0.248)
			(stroke
				(width 0.15)
				(type solid)
			)
			(layer "F.Fab")
		)
		(fp_text user "License: Apache-2.0"
			(at -0.939 5.799 0)
			(layer "F.Fab")
			(effects
				(font
					(size 0.7 0.7)
					(thickness 0.15)
				)
				(justify left bottom)
			)
		)
		(fp_text user "${REFERENCE}"
			(at 0 0 0)
			(layer "F.Fab")
			(effects
				(font
					(size 0.7 0.7)
					(thickness 0.15)
				)
				(justify left bottom)
			)
		)
		(fp_text user "Author: Antmicro"
			(at -0.939 3.399 0)
			(layer "F.Fab")
			(effects
				(font
					(size 0.7 0.7)
					(thickness 0.15)
				)
				(justify left bottom)
			)
		)
		(pad "1" smd roundrect
			(at -0.48 0)
			(size 0.59 0.64)
			(layers "F.Cu" "F.Mask" "F.Paste")
			(roundrect_rratio 0.25)
			(net 66 "GND")
			(pintype "passive")
		)
		(pad "2" smd roundrect
			(at 0.48 0)
			(size 0.59 0.64)
			(layers "F.Cu" "F.Mask" "F.Paste")
			(roundrect_rratio 0.25)
			(net 187 "/USB-PD/12V_CONV")
			(pintype "passive")
		)
	)
	(footprint "antmicro-footprints:PLCC4_3.2x2.8mm"
		(layer "F.Cu")
		(at 137.2 36 90)
		(property "Reference" "D4"
			(at 2.4 -0.75 90)
			(layer "F.SilkS")
			(effects
				(font
					(size 0.7 0.7)
					(thickness 0.15)
				)
				(justify left bottom)
			)
		)
		(property "Value" "LED_RGB_PLCC4_ASMB_MTB1_0A3A2"
			(at 0 2.7 90)
			(unlocked yes)
			(layer "F.Fab")
			(effects
				(font
					(size 0.7 0.7)
					(thickness 0.15)
				)
				(justify left bottom)
			)
		)
		(property "Datasheet" "https://docs.broadcom.com/doc/AV02-4194EN"
			(at 0 0 90)
			(layer "F.Fab")
			(hide yes)
			(effects
				(font
					(size 1.27 1.27)
					(thickness 0.15)
				)
			)
		)
		(property "Description" "LED, RGB, SMD, PLCC-4, R 20 mA, G 20 mA, B 20 mA, R 2.1 V, G 3.1 V, B 3.1 V, Common Anode"
			(at 0 0 90)
			(layer "F.Fab")
			(hide yes)
			(effects
				(font
					(size 1.27 1.27)
					(thickness 0.15)
				)
			)
		)
		(property "MPN" "ASMB-MTB1-0A3A2"
			(at 0 0 90)
			(unlocked yes)
			(layer "F.Fab")
			(hide yes)
			(effects
				(font
					(size 1 1)
					(thickness 0.15)
				)
			)
		)
		(property "Manufacturer" "Avago Technologies"
			(at 0 0 90)
			(unlocked yes)
			(layer "F.Fab")
			(hide yes)
			(effects
				(font
					(size 1 1)
					(thickness 0.15)
				)
			)
		)
		(property "Color" "R, G, B"
			(at 0 0 90)
			(unlocked yes)
			(layer "F.Fab")
			(hide yes)
			(effects
				(font
					(size 1 1)
					(thickness 0.15)
				)
			)
		)
		(property "Author" "Antmicro"
			(at 0 0 90)
			(unlocked yes)
			(layer "F.Fab")
			(hide yes)
			(effects
				(font
					(size 1 1)
					(thickness 0.15)
				)
			)
		)
		(property "License" "Apache-2.0"
			(at 0 0 90)
			(unlocked yes)
			(layer "F.Fab")
			(hide yes)
			(effects
				(font
					(size 1 1)
					(thickness 0.15)
				)
			)
		)
		(sheetname "/USB-PD/")
		(sheetfile "usb-pd.kicad_sch")
		(attr smd)
		(fp_line
			(start -1.75 -1.491)
			(end 1.947 -1.491)
			(stroke
				(width 0.15)
				(type solid)
			)
			(layer "F.SilkS")
		)
		(fp_line
			(start -1.953 1.509)
			(end 1.947 1.509)
			(stroke
				(width 0.15)
				(type solid)
			)
			(layer "F.SilkS")
		)
		(fp_circle
			(center -2 -1.45)
			(end -1.95 -1.45)
			(stroke
				(width 0.15)
				(type solid)
			)
			(fill yes)
			(layer "F.SilkS")
		)
		(fp_rect
			(start -2.25 -1.65)
			(end 2.24 1.65)
			(stroke
				(width 0.05)
				(type solid)
			)
			(fill no)
			(layer "F.CrtYd")
		)
		(fp_line
			(start 1.597 -1.391)
			(end -1.603 -1.391)
			(stroke
				(width 0.15)
				(type solid)
			)
			(layer "F.Fab")
		)
		(fp_line
			(start -0.603 -1.391)
			(end -1.603 -0.391)
			(stroke
				(width 0.15)
				(type solid)
			)
			(layer "F.Fab")
		)
		(fp_line
			(start -1.603 -1.391)
			(end -1.603 1.409)
			(stroke
				(width 0.15)
				(type solid)
			)
			(layer "F.Fab")
		)
		(fp_line
			(start 1.597 1.409)
			(end 1.597 -1.391)
			(stroke
				(width 0.15)
				(type solid)
			)
			(layer "F.Fab")
		)
		(fp_line
			(start -1.603 1.409)
			(end 1.597 1.409)
			(stroke
				(width 0.15)
				(type solid)
			)
			(layer "F.Fab")
		)
		(fp_circle
			(center -0.003 0.009)
			(end 1.117 0.009)
			(stroke
				(width 0.15)
				(type solid)
			)
			(fill no)
			(layer "F.Fab")
		)
		(fp_text user "Author: Antmicro"
			(at -2.6 7.709 90)
			(layer "F.Fab")
			(effects
				(font
					(size 0.7 0.7)
					(thickness 0.15)
				)
				(justify left bottom)
			)
		)
		(fp_text user "License: Apache-2.0"
			(at -2.600001 6.509 90)
			(layer "F.Fab")
			(effects
				(font
					(size 0.7 0.7)
					(thickness 0.15)
				)
				(justify left bottom)
			)
		)
		(fp_text user "${REFERENCE}"
			(at -0.005001 0 90)
			(layer "F.Fab")
			(effects
				(font
					(size 0.7 0.7)
					(thickness 0.15)
				)
				(justify left bottom)
			)
		)
		(pad "1" smd rect
			(at -1.255 -0.74 90)
			(size 1.5 1.1)
			(layers "F.Cu" "F.Mask" "F.Paste")
			(net 167 "Net-(D4-C_{R})")
			(pinfunction "C_{R}")
			(pintype "passive")
		)
		(pad "2" smd rect
			(at 1.245 -0.74 90)
			(size 1.5 1.1)
			(layers "F.Cu" "F.Mask" "F.Paste")
			(net 165 "Net-(D4-C_{G})")
			(pinfunction "C_{G}")
			(pintype "passive")
		)
		(pad "3" smd rect
			(at 1.245 0.76 90)
			(size 1.5 1.1)
			(layers "F.Cu" "F.Mask" "F.Paste")
			(net 166 "unconnected-(D4-C_{B}-Pad3)")
			(pinfunction "C_{B}")
			(pintype "passive+no_connect")
		)
		(pad "4" smd rect
			(at -1.255 0.76 90)
			(size 1.5 1.1)
			(layers "F.Cu" "F.Mask" "F.Paste")
			(net 113 "VBUS")
			(pinfunction "A")
			(pintype "passive")
		)
	)
	(footprint "antmicro-footprints:R_0402_1005Metric"
		(layer "F.Cu")
		(at 118.55 45.75 -90)
		(descr "Resistor SMD 0402")
		(tags "resistor SMD 0402")
		(property "Reference" "R47"
			(at -3.15 0.35 270)
			(layer "F.SilkS")
			(effects
				(font
					(size 0.7 0.7)
					(thickness 0.15)
				)
				(justify right top)
			)
		)
		(property "Value" "R_0R_0402"
			(at -1.011843 1.772046 90)
			(layer "F.Fab")
			(effects
				(font
					(size 0.7 0.7)
					(thickness 0.15)
				)
				(justify right top)
			)
		)
		(property "Datasheet" "https://industrial.panasonic.com/cdbs/www-data/pdf/RDA0000/AOA0000C301.pdf"
			(at 0 0 90)
			(layer "F.Fab")
			(hide yes)
			(effects
				(font
					(size 1.27 1.27)
					(thickness 0.15)
				)
			)
		)
		(property "Description" "SMD Chip Resistor, Jumper, 0 ohm, 100 mW, 0402 [1005 Metric], Thick Film, General Purpose"
			(at 0 0 90)
			(layer "F.Fab")
			(hide yes)
			(effects
				(font
					(size 1.27 1.27)
					(thickness 0.15)
				)
			)
		)
		(property "MPN" "ERJ2GE0R00X"
			(at 0 0 270)
			(unlocked yes)
			(layer "F.Fab")
			(hide yes)
			(effects
				(font
					(size 1 1)
					(thickness 0.15)
				)
			)
		)
		(property "Manufacturer" "Panasonic"
			(at 0 0 270)
			(unlocked yes)
			(layer "F.Fab")
			(hide yes)
			(effects
				(font
					(size 1 1)
					(thickness 0.15)
				)
			)
		)
		(property "License" "Apache-2.0"
			(at 0 0 270)
			(unlocked yes)
			(layer "F.Fab")
			(hide yes)
			(effects
				(font
					(size 1 1)
					(thickness 0.15)
				)
			)
		)
		(property "Author" "Antmicro"
			(at 0 0 270)
			(unlocked yes)
			(layer "F.Fab")
			(hide yes)
			(effects
				(font
					(size 1 1)
					(thickness 0.15)
				)
			)
		)
		(property "Val" "0R"
			(at 0 0 270)
			(unlocked yes)
			(layer "F.Fab")
			(hide yes)
			(effects
				(font
					(size 1 1)
					(thickness 0.15)
				)
			)
		)
		(property "Tolerance" ""
			(at 0 0 270)
			(unlocked yes)
			(layer "F.Fab")
			(hide yes)
			(effects
				(font
					(size 1 1)
					(thickness 0.15)
				)
			)
		)
		(property "Current" "1A"
			(at 0 0 270)
			(unlocked yes)
			(layer "F.Fab")
			(hide yes)
			(effects
				(font
					(size 1 1)
					(thickness 0.15)
				)
			)
		)
		(sheetname "/OCuLink/")
		(sheetfile "oculink.kicad_sch")
		(attr smd)
		(fp_rect
			(start -0.925 -0.47)
			(end 0.925 0.47)
			(stroke
				(width 0.05)
				(type default)
			)
			(fill no)
			(layer "F.CrtYd")
		)
		(fp_rect
			(start -0.5 -0.25)
			(end 0.5 0.25)
			(stroke
				(width 0.15)
				(type solid)
			)
			(fill no)
			(layer "F.Fab")
		)
		(fp_text user "License: Apache-2.0"
			(at -0.949999 5.169 90)
			(layer "F.Fab")
			(effects
				(font
					(size 0.7 0.7)
					(thickness 0.15)
				)
				(justify right top)
			)
		)
		(fp_text user "${REFERENCE}"
			(at 0 0 90)
			(layer "F.Fab")
			(effects
				(font
					(size 0.7 0.7)
					(thickness 0.15)
				)
				(justify right top)
			)
		)
		(fp_text user "Author: Antmicro"
			(at -0.95 4.169 90)
			(layer "F.Fab")
			(effects
				(font
					(size 0.7 0.7)
					(thickness 0.15)
				)
				(justify right top)
			)
		)
		(pad "1" smd roundrect
			(at -0.48 0 270)
			(size 0.59 0.64)
			(layers "F.Cu" "F.Mask" "F.Paste")
			(roundrect_rratio 0.25)
			(net 171 "/OCuLink/PCIe_{REF0}_R.CK-")
			(pintype "passive")
		)
		(pad "2" smd roundrect
			(at 0.48 0 270)
			(size 0.59 0.64)
			(layers "F.Cu" "F.Mask" "F.Paste")
			(roundrect_rratio 0.25)
			(net 97 "/OCuLink/PCIe_{REF0}.CK-")
			(pintype "passive")
		)
	)
	(footprint "antmicro-footprints:TP_Pad0.75mm_Drill0.2mm"
		(layer "F.Cu")
		(at 153.912001 54.476 180)
		(property "Reference" "TP6"
			(at -0.438 -0.274 180)
			(layer "F.SilkS")
			(effects
				(font
					(size 0.7 0.7)
					(thickness 0.15)
				)
				(justify left bottom)
			)
		)
		(property "Value" "TP_Pad0.75mm_Drill0.2mm"
			(at 0 1.2 180)
			(layer "F.Fab")
			(effects
				(font
					(size 0.7 0.7)
					(thickness 0.15)
				)
				(justify left bottom)
			)
		)
		(property "Description" "SMT test point"
			(at 0 0 180)
			(layer "F.Fab")
			(hide yes)
			(effects
				(font
					(size 1.27 1.27)
					(thickness 0.15)
				)
			)
		)
		(property "MPN" ""
			(at 0 0 180)
			(unlocked yes)
			(layer "F.Fab")
			(hide yes)
			(effects
				(font
					(size 1 1)
					(thickness 0.15)
				)
			)
		)
		(property "Manufacturer" ""
			(at 0 0 180)
			(unlocked yes)
			(layer "F.Fab")
			(hide yes)
			(effects
				(font
					(size 1 1)
					(thickness 0.15)
				)
			)
		)
		(property "Author" "Antmicro"
			(at 0 0 180)
			(unlocked yes)
			(layer "F.Fab")
			(hide yes)
			(effects
				(font
					(size 1 1)
					(thickness 0.15)
				)
			)
		)
		(property "License" "Apache-2.0"
			(at 0 0 180)
			(unlocked yes)
			(layer "F.Fab")
			(hide yes)
			(effects
				(font
					(size 1 1)
					(thickness 0.15)
				)
			)
		)
		(sheetname "/USB-PD/")
		(sheetfile "usb-pd.kicad_sch")
		(attr exclude_from_pos_files exclude_from_bom)
		(fp_circle
			(center 0 0)
			(end 0.475 0)
			(stroke
				(width 0.05)
				(type default)
			)
			(fill no)
			(layer "F.CrtYd")
		)
		(fp_text user "License: Apache-2.0"
			(at -0.4 5.101 180)
			(layer "F.Fab")
			(effects
				(font
					(size 0.7 0.7)
					(thickness 0.15)
				)
				(justify left bottom)
			)
		)
		(fp_text user "${REFERENCE}"
			(at -0.4 2.7 180)
			(layer "F.Fab")
			(effects
				(font
					(size 0.7 0.7)
					(thickness 0.15)
				)
				(justify left bottom)
			)
		)
		(fp_text user "Author: Antmicro"
			(at -0.4 3.901 180)
			(layer "F.Fab")
			(effects
				(font
					(size 0.7 0.7)
					(thickness 0.15)
				)
				(justify left bottom)
			)
		)
		(pad "1" thru_hole circle
			(at 0 0 180)
			(size 0.75 0.75)
			(drill 0.2)
			(layers "*.Cu" "*.Mask")
			(remove_unused_layers no)
			(net 145 "/USB-PD/GPIO_1")
			(pinfunction "1")
			(pintype "passive")
		)
	)
)
